# BASEBOARD_FAB2 (Tioga Pass) — schematic netlist excerpt (pin names and nets, part order shuffled) for the footprints in the layout excerpt that follows; sources: Cadence DE-HDL packaged netlist, KiCad conversion of Wiwynn_Tioga_Pass_MB.brd

EU7F1  NCP3232L  IC  pkg SM  page 231
  SS  = VR_PVPP_ABC_SS
  FB  = VR_FB_PVPP_ABC
  COMP  = VR_COMP_PVPP_ABC_3
  ISET  = VR_PVPP_ABC_ISET
  AGND  = AGND_PVPP_ABC
  OTS  = AGND_PVPP_ABC
  PG  = PWRGD_PVPP_ABC_R
  VIN(0)  = VR_FET_SW_P12V_STBY_PVPP_ABC
  VIN(1)  = VR_FET_SW_P12V_STBY_PVPP_ABC
  VIN(2)  = VR_FET_SW_P12V_STBY_PVPP_ABC
  VIN(3)  = VR_FET_SW_P12V_STBY_PVPP_ABC
  VIN(4)  = VR_FET_SW_P12V_STBY_PVPP_ABC
  VIN(5)  = VR_FET_SW_P12V_STBY_PVPP_ABC
  VIN(6)  = VR_FET_SW_P12V_STBY_PVPP_ABC
  VSWH(0)  = VR_PVPP_ABC_PHASE
  PGND(0)  = GND
  PGND(1)  = GND
  PGND(2)  = GND
  PGND(3)  = GND
  PGND(4)  = GND
  PGND(5)  = GND
  PGND(6)  = GND
  PGND(7)  = GND
  PGND(8)  = GND
  PGND(9)  = GND
  PGND(10)  = GND
  PGND(11)  = GND
  PGND(12)  = GND
  VSWH(1)  = VR_PVPP_ABC_PHASE
  VSWH(2)  = VR_PVPP_ABC_PHASE
  VSWH(3)  = VR_PVPP_ABC_PHASE
  VSWH(4)  = VR_PVPP_ABC_PHASE
  VSWH(5)  = VR_PVPP_ABC_PHASE
  VSWH(6)  = VR_PVPP_ABC_PHASE
  VSW  = VR_PVPP_ABC_PHASE
  BST  = VR_PVPP_ABC_BOOT
  PGND(13)  = GND
  VB  = VR_VB_PVPP_ABC
  VCC  = VR_FET_SW_P12V_STBY_PVPP_ABC
  EN  = FM_PVPP_PVDDQ_CPU0_EN_ABC
  GND  = GND
  VIN(7)  = VR_FET_SW_P12V_STBY_PVPP_ABC
  VSWH(7)  = VR_PVPP_ABC_PHASE

(kicad_pcb
	(version 20260206)
	(generator "pcbnew")
	(generator_version "10.0")
	(general
		(thickness 1.6)
		(legacy_teardrops no)
	)
	(paper "A4")
	(title_block
		(title "Wiwynn_Tioga_Pass_MB.brd")
		(comment 1 "Tioga Pass / footprint 636 of 4770 (EU7F1), pads 18-35 of 43")
	)
	(layers
		(0 "F.Cu" signal "TOP")
		(4 "In1.Cu" signal "L2GND")
		(6 "In2.Cu" signal "L3")
		(8 "In3.Cu" signal "L4GND")
		(10 "In4.Cu" signal "L5")
		(12 "In5.Cu" signal "L6GND")
		(14 "In6.Cu" signal "L7VCC")
		(16 "In7.Cu" signal "L8VCC")
		(18 "In8.Cu" signal "L9GND")
		(20 "In9.Cu" signal "L10")
		(22 "In10.Cu" signal "L11GND")
		(24 "In11.Cu" signal "L12")
		(26 "In12.Cu" signal "L13GND")
		(2 "B.Cu" signal "BOTTOM")
		(9 "F.Adhes" user "F.Adhesive")
		(11 "B.Adhes" user "B.Adhesive")
		(13 "F.Paste" user "Package Geometry/Pastemask Top")
		(15 "B.Paste" user "Package Geometry/Pastemask Bottom")
		(5 "F.SilkS" user "Ref Des/Silkscreen Top")
		(7 "B.SilkS" user "Ref Des/Silkscreen Bottom")
		(1 "F.Mask" user "Board Geometry/Soldermask Top")
		(3 "B.Mask" user "Board Geometry/Soldermask Bottom")
		(17 "Dwgs.User" user "User.Drawings")
		(19 "Cmts.User" user "User.Comments")
		(21 "Eco1.User" user "User.Eco1")
		(23 "Eco2.User" user "User.Eco2")
		(25 "Edge.Cuts" user "Board Geometry/Outline")
		(27 "Margin" user)
		(31 "F.CrtYd" user "Package Geometry/Place Bound Top")
		(29 "B.CrtYd" user "Package Geometry/Place Bound Bottom")
		(35 "F.Fab" user "Ref Des/Assembly Top")
		(33 "B.Fab" user "Ref Des/Assembly Bottom")
	)
	(footprint ""
		(layer "F.Cu")
		(at 345.3638 -28.5623 90)
		(property "Reference" "EU7F1"
			(at 5.27939 -1.76022 0)
			(unlocked yes)
			(layer "F.SilkS")
			(effects
				(font
					(size 0.7874 0.5842)
					(thickness 0.1524)
				)
				(justify left)
			)
		)
		(property "Value" ""
			(at 0 0 90)
			(layer "F.Fab")
			(effects
				(font
					(size 1.27 1.27)
				)
			)
		)
		(duplicate_pad_numbers_are_jumpers no)
		(pad "18" smd custom
			(at 1.249934 2.8321 90)
			(size 0.06985 0.06985)
			(layers "F.Cu" "F.Mask" "F.Paste")
			(net "GND")
			(options
				(clearance outline)
				(anchor circle)
			)
			(primitives
				(gr_poly
					(pts
						(arc
							(start -0.1397 -0.2413)
							(mid 0 -0.381)
							(end 0.1397 -0.2413)
						)
						(xy 0.1397 0.381) (xy -0.1397 0.381)
					)
					(width 0)
					(fill yes)
				)
			)
		)
		(pad "19" smd custom
			(at 1.75006 2.8321 90)
			(size 0.06985 0.06985)
			(layers "F.Cu" "F.Mask" "F.Paste")
			(net "GND")
			(options
				(clearance outline)
				(anchor circle)
			)
			(primitives
				(gr_poly
					(pts
						(arc
							(start -0.1397 -0.2413)
							(mid 0 -0.381)
							(end 0.1397 -0.2413)
						)
						(xy 0.1397 0.381) (xy -0.1397 0.381)
					)
					(width 0)
					(fill yes)
				)
			)
		)
		(pad "20" smd custom
			(at 2.249932 2.8321 90)
			(size 0.06985 0.06985)
			(layers "F.Cu" "F.Mask" "F.Paste")
			(net "GND")
			(options
				(clearance outline)
				(anchor circle)
			)
			(primitives
				(gr_poly
					(pts
						(arc
							(start -0.1397 -0.2413)
							(mid 0 -0.381)
							(end 0.1397 -0.2413)
						)
						(xy 0.1397 0.381) (xy -0.1397 0.381)
					)
					(width 0)
					(fill yes)
				)
			)
		)
		(pad "21" smd custom
			(at 2.8321 2.249932 90)
			(size 0.06985 0.06985)
			(layers "F.Cu" "F.Mask" "F.Paste")
			(net "GND")
			(options
				(clearance outline)
				(anchor circle)
			)
			(primitives
				(gr_poly
					(pts
						(arc
							(start -0.2413 0.1397)
							(mid -0.381 0)
							(end -0.2413 -0.1397)
						)
						(xy 0.381 -0.1397) (xy 0.381 0.1397)
					)
					(width 0)
					(fill yes)
				)
			)
		)
		(pad "22" smd custom
			(at 2.8321 1.75006 90)
			(size 0.06985 0.06985)
			(layers "F.Cu" "F.Mask" "F.Paste")
			(net "GND")
			(options
				(clearance outline)
				(anchor circle)
			)
			(primitives
				(gr_poly
					(pts
						(arc
							(start -0.2413 0.1397)
							(mid -0.381 0)
							(end -0.2413 -0.1397)
						)
						(xy 0.381 -0.1397) (xy 0.381 0.1397)
					)
					(width 0)
					(fill yes)
				)
			)
		)
		(pad "23" smd custom
			(at 2.8321 1.249934 90)
			(size 0.06985 0.06985)
			(layers "F.Cu" "F.Mask" "F.Paste")
			(net "GND")
			(options
				(clearance outline)
				(anchor circle)
			)
			(primitives
				(gr_poly
					(pts
						(arc
							(start -0.2413 0.1397)
							(mid -0.381 0)
							(end -0.2413 -0.1397)
						)
						(xy 0.381 -0.1397) (xy 0.381 0.1397)
					)
					(width 0)
					(fill yes)
				)
			)
		)
		(pad "24" smd custom
			(at 2.8321 0.750062 90)
			(size 0.06985 0.06985)
			(layers "F.Cu" "F.Mask" "F.Paste")
			(net "GND")
			(options
				(clearance outline)
				(anchor circle)
			)
			(primitives
				(gr_poly
					(pts
						(arc
							(start -0.2413 0.1397)
							(mid -0.381 0)
							(end -0.2413 -0.1397)
						)
						(xy 0.381 -0.1397) (xy 0.381 0.1397)
					)
					(width 0)
					(fill yes)
				)
			)
		)
		(pad "25" smd custom
			(at 2.8321 0.249936 90)
			(size 0.06985 0.06985)
			(layers "F.Cu" "F.Mask" "F.Paste")
			(net "GND")
			(options
				(clearance outline)
				(anchor circle)
			)
			(primitives
				(gr_poly
					(pts
						(arc
							(start -0.2413 0.1397)
							(mid -0.381 0)
							(end -0.2413 -0.1397)
						)
						(xy 0.381 -0.1397) (xy 0.381 0.1397)
					)
					(width 0)
					(fill yes)
				)
			)
		)
		(pad "26" smd custom
			(at 2.8321 -0.249936 90)
			(size 0.06985 0.06985)
			(layers "F.Cu" "F.Mask" "F.Paste")
			(net "GND")
			(options
				(clearance outline)
				(anchor circle)
			)
			(primitives
				(gr_poly
					(pts
						(arc
							(start -0.2413 0.1397)
							(mid -0.381 0)
							(end -0.2413 -0.1397)
						)
						(xy 0.381 -0.1397) (xy 0.381 0.1397)
					)
					(width 0)
					(fill yes)
				)
			)
		)
		(pad "27" smd custom
			(at 2.8321 -0.750062 90)
			(size 0.06985 0.06985)
			(layers "F.Cu" "F.Mask" "F.Paste")
			(net "GND")
			(options
				(clearance outline)
				(anchor circle)
			)
			(primitives
				(gr_poly
					(pts
						(arc
							(start -0.2413 0.1397)
							(mid -0.381 0)
							(end -0.2413 -0.1397)
						)
						(xy 0.381 -0.1397) (xy 0.381 0.1397)
					)
					(width 0)
					(fill yes)
				)
			)
		)
		(pad "28" smd custom
			(at 2.8321 -1.249934 90)
			(size 0.06985 0.06985)
			(layers "F.Cu" "F.Mask" "F.Paste")
			(net "GND")
			(options
				(clearance outline)
				(anchor circle)
			)
			(primitives
				(gr_poly
					(pts
						(arc
							(start -0.2413 0.1397)
							(mid -0.381 0)
							(end -0.2413 -0.1397)
						)
						(xy 0.381 -0.1397) (xy 0.381 0.1397)
					)
					(width 0)
					(fill yes)
				)
			)
		)
		(pad "29" smd custom
			(at 2.8321 -1.75006 90)
			(size 0.06985 0.06985)
			(layers "F.Cu" "F.Mask" "F.Paste")
			(net "VR_PVPP_ABC_PHASE")
			(options
				(clearance outline)
				(anchor circle)
			)
			(primitives
				(gr_poly
					(pts
						(arc
							(start -0.2413 0.1397)
							(mid -0.381 0)
							(end -0.2413 -0.1397)
						)
						(xy 0.381 -0.1397) (xy 0.381 0.1397)
					)
					(width 0)
					(fill yes)
				)
			)
		)
		(pad "30" smd custom
			(at 2.8321 -2.249932 90)
			(size 0.06985 0.06985)
			(layers "F.Cu" "F.Mask" "F.Paste")
			(net "VR_PVPP_ABC_PHASE")
			(options
				(clearance outline)
				(anchor circle)
			)
			(primitives
				(gr_poly
					(pts
						(arc
							(start -0.2413 0.1397)
							(mid -0.381 0)
							(end -0.2413 -0.1397)
						)
						(xy 0.381 -0.1397) (xy 0.381 0.1397)
					)
					(width 0)
					(fill yes)
				)
			)
		)
		(pad "31" smd custom
			(at 2.249932 -2.8321 90)
			(size 0.06985 0.06985)
			(layers "F.Cu" "F.Mask" "F.Paste")
			(net "VR_PVPP_ABC_PHASE")
			(options
				(clearance outline)
				(anchor circle)
			)
			(primitives
				(gr_poly
					(pts
						(arc
							(start 0.1397 0.2413)
							(mid 0 0.381)
							(end -0.1397 0.2413)
						)
						(xy -0.1397 -0.381) (xy 0.1397 -0.381)
					)
					(width 0)
					(fill yes)
				)
			)
		)
		(pad "32" smd custom
			(at 1.75006 -2.8321 90)
			(size 0.06985 0.06985)
			(layers "F.Cu" "F.Mask" "F.Paste")
			(net "VR_PVPP_ABC_PHASE")
			(options
				(clearance outline)
				(anchor circle)
			)
			(primitives
				(gr_poly
					(pts
						(arc
							(start 0.1397 0.2413)
							(mid 0 0.381)
							(end -0.1397 0.2413)
						)
						(xy -0.1397 -0.381) (xy 0.1397 -0.381)
					)
					(width 0)
					(fill yes)
				)
			)
		)
		(pad "33" smd custom
			(at 1.249934 -2.8321 90)
			(size 0.06985 0.06985)
			(layers "F.Cu" "F.Mask" "F.Paste")
			(net "VR_PVPP_ABC_PHASE")
			(options
				(clearance outline)
				(anchor circle)
			)
			(primitives
				(gr_poly
					(pts
						(arc
							(start 0.1397 0.2413)
							(mid 0 0.381)
							(end -0.1397 0.2413)
						)
						(xy -0.1397 -0.381) (xy 0.1397 -0.381)
					)
					(width 0)
					(fill yes)
				)
			)
		)
		(pad "34" smd custom
			(at 0.750062 -2.8321 90)
			(size 0.06985 0.06985)
			(layers "F.Cu" "F.Mask" "F.Paste")
			(net "VR_PVPP_ABC_PHASE")
			(options
				(clearance outline)
				(anchor circle)
			)
			(primitives
				(gr_poly
					(pts
						(arc
							(start 0.1397 0.2413)
							(mid 0 0.381)
							(end -0.1397 0.2413)
						)
						(xy -0.1397 -0.381) (xy 0.1397 -0.381)
					)
					(width 0)
					(fill yes)
				)
			)
		)
		(pad "35" smd custom
			(at 0.249936 -2.8321 90)
			(size 0.06985 0.06985)
			(layers "F.Cu" "F.Mask" "F.Paste")
			(net "VR_PVPP_ABC_PHASE")
			(options
				(clearance outline)
				(anchor circle)
			)
			(primitives
				(gr_poly
					(pts
						(arc
							(start 0.1397 0.2413)
							(mid 0 0.381)
							(end -0.1397 0.2413)
						)
						(xy -0.1397 -0.381) (xy 0.1397 -0.381)
					)
					(width 0)
					(fill yes)
				)
			)
		)
	)
)
